(kicad_pcb
	(version 20241229)
	(generator "pcbnew")
	(generator_version "9.0")
	(general
		(thickness 1.711)
		(legacy_teardrops no)
	)
	(paper "A4")
	(title_block
		(title "Antmicro Baseboard for Jetson AGX Thor")
		(date "2026-02-18")
		(rev "1.1.0")
		(company "Antmicro Ltd")
		(comment 1 "www.antmicro.com")
		(comment 9 "footprints 376-380 of 1170")
	)
	(layers
		(0 "F.Cu" signal)
		(4 "In1.Cu" signal)
		(6 "In2.Cu" signal)
		(8 "In3.Cu" signal)
		(10 "In4.Cu" jumper)
		(12 "In5.Cu" signal)
		(14 "In6.Cu" signal)
		(16 "In7.Cu" signal)
		(18 "In8.Cu" signal)
		(2 "B.Cu" signal)
		(9 "F.Adhes" user "F.Adhesive")
		(11 "B.Adhes" user "B.Adhesive")
		(13 "F.Paste" user)
		(15 "B.Paste" user)
		(5 "F.SilkS" user "F.Silkscreen")
		(7 "B.SilkS" user "B.Silkscreen")
		(1 "F.Mask" user)
		(3 "B.Mask" user)
		(17 "Dwgs.User" user "User.Drawings")
		(19 "Cmts.User" user "User.Comments")
		(21 "Eco1.User" user "User.Eco1")
		(23 "Eco2.User" user "User.Eco2")
		(25 "Edge.Cuts" user)
		(27 "Margin" user)
		(31 "F.CrtYd" user "F.Courtyard")
		(29 "B.CrtYd" user "B.Courtyard")
		(35 "F.Fab" user)
		(33 "B.Fab" user)
	)
	(footprint "antmicro-footprints:R_0402_1005Metric"
		(layer "F.Cu")
		(at 195.1 128.3 180)
		(descr "Resistor SMD 0402")
		(tags "resistor SMD 0402")
		(property "Reference" "R89"
			(at -1.1 -4.6 0)
			(layer "F.SilkS")
			(effects
				(font
					(size 0.7 0.7)
					(thickness 0.15)
				)
				(justify right top)
			)
		)
		(property "Value" "R_0R_0402"
			(at -1.011843 1.772047 0)
			(layer "F.Fab")
			(effects
				(font
					(size 0.7 0.7)
					(thickness 0.15)
				)
				(justify right top)
			)
		)
		(property "Datasheet" "https://industrial.panasonic.com/cdbs/www-data/pdf/RDA0000/AOA0000C301.pdf"
			(at 0 0 0)
			(layer "F.Fab")
			(hide yes)
			(effects
				(font
					(size 1.27 1.27)
					(thickness 0.15)
				)
			)
		)
		(property "Description" "SMD Chip Resistor, Jumper, 0 ohm, 100 mW, 0402 [1005 Metric], Thick Film, General Purpose"
			(at 0 0 0)
			(layer "F.Fab")
			(hide yes)
			(effects
				(font
					(size 1.27 1.27)
					(thickness 0.15)
				)
			)
		)
		(property "Manufacturer" "Panasonic"
			(at 0 0 180)
			(unlocked yes)
			(layer "F.Fab")
			(hide yes)
			(effects
				(font
					(size 1 1)
					(thickness 0.15)
				)
			)
		)
		(property "MPN" "ERJ2GE0R00X"
			(at 0 0 180)
			(unlocked yes)
			(layer "F.Fab")
			(hide yes)
			(effects
				(font
					(size 1 1)
					(thickness 0.15)
				)
			)
		)
		(property "Val" "0R"
			(at 0 0 180)
			(unlocked yes)
			(layer "F.Fab")
			(hide yes)
			(effects
				(font
					(size 1 1)
					(thickness 0.15)
				)
			)
		)
		(property "License" "Apache-2.0"
			(at 0 0 180)
			(unlocked yes)
			(layer "F.Fab")
			(hide yes)
			(effects
				(font
					(size 1 1)
					(thickness 0.15)
				)
			)
		)
		(property "Author" "Antmicro"
			(at 0 0 180)
			(unlocked yes)
			(layer "F.Fab")
			(hide yes)
			(effects
				(font
					(size 1 1)
					(thickness 0.15)
				)
			)
		)
		(property "Tolerance" "~"
			(at 0 0 180)
			(unlocked yes)
			(layer "F.Fab")
			(hide yes)
			(effects
				(font
					(size 1 1)
					(thickness 0.15)
				)
			)
		)
		(property "Current" "1A"
			(at 0 0 180)
			(unlocked yes)
			(layer "F.Fab")
			(hide yes)
			(effects
				(font
					(size 1 1)
					(thickness 0.15)
				)
			)
		)
		(sheetname "/USB Hub/")
		(sheetfile "usb_hub.kicad_sch")
		(attr smd exclude_from_pos_files exclude_from_bom dnp)
		(fp_rect
			(start -0.925 -0.47)
			(end 0.925 0.47)
			(stroke
				(width 0.05)
				(type default)
			)
			(fill no)
			(layer "F.CrtYd")
		)
		(fp_rect
			(start -0.5 -0.25)
			(end 0.5 0.25)
			(stroke
				(width 0.15)
				(type solid)
			)
			(fill no)
			(layer "F.Fab")
		)
		(fp_text user "${REFERENCE}"
			(at -0.95 3.168 0)
			(layer "F.Fab")
			(effects
				(font
					(size 0.7 0.7)
					(thickness 0.15)
				)
				(justify right top)
			)
		)
		(fp_text user "Author: Antmicro"
			(at -0.95 4.169 0)
			(layer "F.Fab")
			(effects
				(font
					(size 0.7 0.7)
					(thickness 0.15)
				)
				(justify right top)
			)
		)
		(fp_text user "License: Apache-2.0"
			(at -0.95 5.169 0)
			(layer "F.Fab")
			(effects
				(font
					(size 0.7 0.7)
					(thickness 0.15)
				)
				(justify right top)
			)
		)
		(pad "1" smd roundrect
			(at -0.48 0 180)
			(size 0.59 0.64)
			(layers "F.Cu" "F.Mask" "F.Paste")
			(roundrect_rratio 0.25)
			(net 927 "/USB Hub/HUB_SPI_CLK")
			(pintype "passive")
		)
		(pad "2" smd roundrect
			(at 0.48 0 180)
			(size 0.59 0.64)
			(layers "F.Cu" "F.Mask" "F.Paste")
			(roundrect_rratio 0.25)
			(net 928 "/USB Debug, PD/SPI_{HUB_DEBUG}.SCK")
			(pintype "passive")
		)
	)
	(footprint "antmicro-footprints:R_0402_1005Metric"
		(layer "F.Cu")
		(at 178.194468 86.455 180)
		(descr "Resistor SMD 0402")
		(tags "resistor SMD 0402")
		(property "Reference" "R26"
			(at -1.06 2.14 0)
			(layer "F.SilkS")
			(effects
				(font
					(size 0.7 0.7)
					(thickness 0.15)
				)
				(justify right top)
			)
		)
		(property "Value" "R_499k_0402"
			(at -1.011843 1.772047 0)
			(layer "F.Fab")
			(effects
				(font
					(size 0.7 0.7)
					(thickness 0.15)
				)
				(justify right top)
			)
		)
		(property "Datasheet" "https://www.mouser.com/datasheet/2/54/cr-1858361.pdf"
			(at 0 0 0)
			(layer "F.Fab")
			(hide yes)
			(effects
				(font
					(size 1.27 1.27)
					(thickness 0.15)
				)
			)
		)
		(property "Description" "SMD Chip Resistor, 499 kohm, ± 1%, 63 mW, 0402 [1005 Metric], Thick Film, General Purpose"
			(at 0 0 0)
			(layer "F.Fab")
			(hide yes)
			(effects
				(font
					(size 1.27 1.27)
					(thickness 0.15)
				)
			)
		)
		(property "MPN" "CR0402-FX-4993GLF"
			(at 0 0 180)
			(unlocked yes)
			(layer "F.Fab")
			(hide yes)
			(effects
				(font
					(size 1 1)
					(thickness 0.15)
				)
			)
		)
		(property "Manufacturer" "Bourns"
			(at 0 0 180)
			(unlocked yes)
			(layer "F.Fab")
			(hide yes)
			(effects
				(font
					(size 1 1)
					(thickness 0.15)
				)
			)
		)
		(property "License" "Apache-2.0"
			(at 0 0 180)
			(unlocked yes)
			(layer "F.Fab")
			(hide yes)
			(effects
				(font
					(size 1 1)
					(thickness 0.15)
				)
			)
		)
		(property "Author" "Antmicro"
			(at 0 0 180)
			(unlocked yes)
			(layer "F.Fab")
			(hide yes)
			(effects
				(font
					(size 1 1)
					(thickness 0.15)
				)
			)
		)
		(property "Val" "499k"
			(at 0 0 180)
			(unlocked yes)
			(layer "F.Fab")
			(hide yes)
			(effects
				(font
					(size 1 1)
					(thickness 0.15)
				)
			)
		)
		(property "Tolerance" "1%"
			(at 0 0 180)
			(unlocked yes)
			(layer "F.Fab")
			(hide yes)
			(effects
				(font
					(size 1 1)
					(thickness 0.15)
				)
			)
		)
		(component_classes
			(class "DCDC_SOM")
		)
		(sheetname "/DCDC/")
		(sheetfile "dcdc.kicad_sch")
		(attr smd exclude_from_pos_files exclude_from_bom dnp)
		(fp_rect
			(start -0.925 -0.47)
			(end 0.925 0.47)
			(stroke
				(width 0.05)
				(type default)
			)
			(fill no)
			(layer "F.CrtYd")
		)
		(fp_rect
			(start -0.5 -0.25)
			(end 0.5 0.25)
			(stroke
				(width 0.15)
				(type solid)
			)
			(fill no)
			(layer "F.Fab")
		)
		(fp_text user "${REFERENCE}"
			(at -0.95 3.168 0)
			(layer "F.Fab")
			(effects
				(font
					(size 0.7 0.7)
					(thickness 0.15)
				)
				(justify right top)
			)
		)
		(fp_text user "License: Apache-2.0"
			(at -0.95 5.169 0)
			(layer "F.Fab")
			(effects
				(font
					(size 0.7 0.7)
					(thickness 0.15)
				)
				(justify right top)
			)
		)
		(fp_text user "Author: Antmicro"
			(at -0.95 4.169 0)
			(layer "F.Fab")
			(effects
				(font
					(size 0.7 0.7)
					(thickness 0.15)
				)
				(justify right top)
			)
		)
		(pad "1" smd roundrect
			(at -0.48 0 180)
			(size 0.59 0.64)
			(layers "F.Cu" "F.Mask" "F.Paste")
			(roundrect_rratio 0.25)
			(net 1207 "/DCDC/16V_MODE1")
			(pintype "passive")
		)
		(pad "2" smd roundrect
			(at 0.48 0 180)
			(size 0.59 0.64)
			(layers "F.Cu" "F.Mask" "F.Paste")
			(roundrect_rratio 0.25)
			(net 896 "/DCDC/16V_VDD")
			(pintype "passive")
		)
	)
	(footprint "antmicro-footprints:C_0402_1005Metric"
		(layer "F.Cu")
		(at 204.75 87.970856 180)
		(descr "Capacitor SMD 0402")
		(tags "capacitor SMD 0402")
		(property "Reference" "C315"
			(at 5.15 -0.429144 180)
			(layer "F.SilkS")
			(effects
				(font
					(size 0.7 0.7)
					(thickness 0.15)
				)
				(justify left bottom)
			)
		)
		(property "Value" "C_100n_0402"
			(at -1.022927 2.155213 180)
			(layer "F.Fab")
			(effects
				(font
					(size 0.7 0.7)
					(thickness 0.15)
				)
				(justify left bottom)
			)
		)
		(property "Datasheet" "https://www.murata.com/products/productdetail?partno=GRM155R61H104KE14%23"
			(at 0 0 180)
			(layer "F.Fab")
			(hide yes)
			(effects
				(font
					(size 1.27 1.27)
					(thickness 0.15)
				)
			)
		)
		(property "Description" "SMD Multilayer Ceramic Capacitor, 0.1 µF, 50 V, 0402 [1005 Metric], ± 10%, X5R, GRM Series"
			(at 0 0 180)
			(layer "F.Fab")
			(hide yes)
			(effects
				(font
					(size 1.27 1.27)
					(thickness 0.15)
				)
			)
		)
		(property "Manufacturer" "Murata"
			(at 0 0 180)
			(unlocked yes)
			(layer "F.Fab")
			(hide yes)
			(effects
				(font
					(size 1 1)
					(thickness 0.15)
				)
			)
		)
		(property "MPN" "GRM155R61H104KE14D"
			(at 0 0 180)
			(unlocked yes)
			(layer "F.Fab")
			(hide yes)
			(effects
				(font
					(size 1 1)
					(thickness 0.15)
				)
			)
		)
		(property "Val" "100n"
			(at 0 0 180)
			(unlocked yes)
			(layer "F.Fab")
			(hide yes)
			(effects
				(font
					(size 1 1)
					(thickness 0.15)
				)
			)
		)
		(property "License" "Apache-2.0"
			(at 0 0 180)
			(unlocked yes)
			(layer "F.Fab")
			(hide yes)
			(effects
				(font
					(size 1 1)
					(thickness 0.15)
				)
			)
		)
		(property "Author" "Antmicro"
			(at 0 0 180)
			(unlocked yes)
			(layer "F.Fab")
			(hide yes)
			(effects
				(font
					(size 1 1)
					(thickness 0.15)
				)
			)
		)
		(property "Voltage" "50V"
			(at 0 0 180)
			(unlocked yes)
			(layer "F.Fab")
			(hide yes)
			(effects
				(font
					(size 1 1)
					(thickness 0.15)
				)
			)
		)
		(property "Dielectric" "X5R"
			(at 0 0 180)
			(unlocked yes)
			(layer "F.Fab")
			(hide yes)
			(effects
				(font
					(size 1 1)
					(thickness 0.15)
				)
			)
		)
		(sheetname "/SoM_IO2/")
		(sheetfile "som_io2.kicad_sch")
		(attr smd)
		(fp_rect
			(start -0.925 -0.47)
			(end 0.925 0.47)
			(stroke
				(width 0.05)
				(type default)
			)
			(fill no)
			(layer "F.CrtYd")
		)
		(fp_line
			(start 0.504 0.248)
			(end -0.494 0.248)
			(stroke
				(width 0.15)
				(type solid)
			)
			(layer "F.Fab")
		)
		(fp_line
			(start 0.504 -0.25)
			(end 0.504 0.248)
			(stroke
				(width 0.15)
				(type solid)
			)
			(layer "F.Fab")
		)
		(fp_line
			(start -0.494 0.248)
			(end -0.494 -0.25)
			(stroke
				(width 0.15)
				(type solid)
			)
			(layer "F.Fab")
		)
		(fp_line
			(start -0.494 -0.25)
			(end 0.504 -0.25)
			(stroke
				(width 0.15)
				(type solid)
			)
			(layer "F.Fab")
		)
		(fp_text user "${REFERENCE}"
			(at -0.939 4.599 180)
			(layer "F.Fab")
			(effects
				(font
					(size 0.7 0.7)
					(thickness 0.15)
				)
				(justify left bottom)
			)
		)
		(fp_text user "Author: Antmicro"
			(at -0.939 3.399 180)
			(layer "F.Fab")
			(effects
				(font
					(size 0.7 0.7)
					(thickness 0.15)
				)
				(justify left bottom)
			)
		)
		(fp_text user "License: Apache-2.0"
			(at -0.939 5.799 180)
			(layer "F.Fab")
			(effects
				(font
					(size 0.7 0.7)
					(thickness 0.15)
				)
				(justify left bottom)
			)
		)
		(pad "1" smd roundrect
			(at -0.48 0 180)
			(size 0.59 0.64)
			(layers "F.Cu" "F.Mask" "F.Paste")
			(roundrect_rratio 0.25)
			(net 663 "/SoM_IO2/DP0.TX0-")
			(pintype "passive")
		)
		(pad "2" smd roundrect
			(at 0.48 0 180)
			(size 0.59 0.64)
			(layers "F.Cu" "F.Mask" "F.Paste")
			(roundrect_rratio 0.25)
			(net 575 "/SoM_IO2/DP0.TX0_C-")
			(pintype "passive")
		)
	)
	(footprint "antmicro-footprints:R_0402_1005Metric"
		(layer "F.Cu")
		(at 219.77 74.699951 180)
		(descr "Resistor SMD 0402")
		(tags "resistor SMD 0402")
		(property "Reference" "R120"
			(at 1.33 -2.685049 180)
			(layer "F.SilkS")
			(effects
				(font
					(size 0.7 0.7)
					(thickness 0.15)
				)
				(justify left bottom)
			)
		)
		(property "Value" "R_200R_0402"
			(at -1.011843 1.772047 180)
			(layer "F.Fab")
			(effects
				(font
					(size 0.7 0.7)
					(thickness 0.15)
				)
				(justify left bottom)
			)
		)
		(property "Datasheet" "https://www.bourns.com/docs/product-datasheets/cr.pdf"
			(at 0 0 180)
			(layer "F.Fab")
			(hide yes)
			(effects
				(font
					(size 1.27 1.27)
					(thickness 0.15)
				)
			)
		)
		(property "Description" "SMD Chip Resistor, 200 ohm, ± 1%, 62.5 mW, 0402 [1005 Metric], Thick Film, General Purpose"
			(at 0 0 180)
			(layer "F.Fab")
			(hide yes)
			(effects
				(font
					(size 1.27 1.27)
					(thickness 0.15)
				)
			)
		)
		(property "Manufacturer" "Bourns"
			(at 0 0 180)
			(unlocked yes)
			(layer "F.Fab")
			(hide yes)
			(effects
				(font
					(size 1 1)
					(thickness 0.15)
				)
			)
		)
		(property "MPN" "CR0402-FX-2000GLF"
			(at 0 0 180)
			(unlocked yes)
			(layer "F.Fab")
			(hide yes)
			(effects
				(font
					(size 1 1)
					(thickness 0.15)
				)
			)
		)
		(property "Val" "200R"
			(at 0 0 180)
			(unlocked yes)
			(layer "F.Fab")
			(hide yes)
			(effects
				(font
					(size 1 1)
					(thickness 0.15)
				)
			)
		)
		(property "License" "Apache-2.0"
			(at 0 0 180)
			(unlocked yes)
			(layer "F.Fab")
			(hide yes)
			(effects
				(font
					(size 1 1)
					(thickness 0.15)
				)
			)
		)
		(property "Author" "Antmicro"
			(at 0 0 180)
			(unlocked yes)
			(layer "F.Fab")
			(hide yes)
			(effects
				(font
					(size 1 1)
					(thickness 0.15)
				)
			)
		)
		(property "Tolerance" "1%"
			(at 0 0 180)
			(unlocked yes)
			(layer "F.Fab")
			(hide yes)
			(effects
				(font
					(size 1 1)
					(thickness 0.15)
				)
			)
		)
		(sheetname "/USB Debug, PD/")
		(sheetfile "usb_debug_pd.kicad_sch")
		(attr smd)
		(fp_rect
			(start -0.925 -0.47)
			(end 0.925 0.47)
			(stroke
				(width 0.05)
				(type default)
			)
			(fill no)
			(layer "F.CrtYd")
		)
		(fp_rect
			(start -0.5 -0.25)
			(end 0.5 0.25)
			(stroke
				(width 0.15)
				(type solid)
			)
			(fill no)
			(layer "F.Fab")
		)
		(fp_text user "Author: Antmicro"
			(at -0.95 4.169 180)
			(layer "F.Fab")
			(effects
				(font
					(size 0.7 0.7)
					(thickness 0.15)
				)
				(justify left bottom)
			)
		)
		(fp_text user "License: Apache-2.0"
			(at -0.95 5.169 180)
			(layer "F.Fab")
			(effects
				(font
					(size 0.7 0.7)
					(thickness 0.15)
				)
				(justify left bottom)
			)
		)
		(fp_text user "${REFERENCE}"
			(at -0.95 3.168 180)
			(layer "F.Fab")
			(effects
				(font
					(size 0.7 0.7)
					(thickness 0.15)
				)
				(justify left bottom)
			)
		)
		(pad "1" smd roundrect
			(at -0.48 0 180)
			(size 0.59 0.64)
			(layers "F.Cu" "F.Mask" "F.Paste")
			(roundrect_rratio 0.25)
			(net 538 "Net-(D21-A)")
			(pintype "passive")
		)
		(pad "2" smd roundrect
			(at 0.48 0 180)
			(size 0.59 0.64)
			(layers "F.Cu" "F.Mask" "F.Paste")
			(roundrect_rratio 0.25)
			(net 334 "/USB Debug, PD/FTDI_3V3")
			(pintype "passive")
		)
	)
	(footprint "antmicro-footprints:C_0402_1005Metric"
		(layer "F.Cu")
		(at 179.469468 139.93)
		(descr "Capacitor SMD 0402")
		(tags "capacitor SMD 0402")
		(property "Reference" "C221"
			(at -3.569468 0.17 0)
			(layer "F.SilkS")
			(effects
				(font
					(size 0.7 0.7)
					(thickness 0.15)
				)
				(justify left bottom)
			)
		)
		(property "Value" "C_100n_0402"
			(at -1.022927 2.155213 0)
			(layer "F.Fab")
			(effects
				(font
					(size 0.7 0.7)
					(thickness 0.15)
				)
				(justify left bottom)
			)
		)
		(property "Datasheet" "https://www.murata.com/products/productdetail?partno=GRM155R61H104KE14%23"
			(at 0 0 0)
			(layer "F.Fab")
			(hide yes)
			(effects
				(font
					(size 1.27 1.27)
					(thickness 0.15)
				)
			)
		)
		(property "Description" "SMD Multilayer Ceramic Capacitor, 0.1 µF, 50 V, 0402 [1005 Metric], ± 10%, X5R, GRM Series"
			(at 0 0 0)
			(layer "F.Fab")
			(hide yes)
			(effects
				(font
					(size 1.27 1.27)
					(thickness 0.15)
				)
			)
		)
		(property "Manufacturer" "Murata"
			(at 0 0 0)
			(unlocked yes)
			(layer "F.Fab")
			(hide yes)
			(effects
				(font
					(size 1 1)
					(thickness 0.15)
				)
			)
		)
		(property "MPN" "GRM155R61H104KE14D"
			(at 0 0 0)
			(unlocked yes)
			(layer "F.Fab")
			(hide yes)
			(effects
				(font
					(size 1 1)
					(thickness 0.15)
				)
			)
		)
		(property "Val" "100n"
			(at 0 0 0)
			(unlocked yes)
			(layer "F.Fab")
			(hide yes)
			(effects
				(font
					(size 1 1)
					(thickness 0.15)
				)
			)
		)
		(property "License" "Apache-2.0"
			(at 0 0 0)
			(unlocked yes)
			(layer "F.Fab")
			(hide yes)
			(effects
				(font
					(size 1 1)
					(thickness 0.15)
				)
			)
		)
		(property "Author" "Antmicro"
			(at 0 0 0)
			(unlocked yes)
			(layer "F.Fab")
			(hide yes)
			(effects
				(font
					(size 1 1)
					(thickness 0.15)
				)
			)
		)
		(property "Voltage" "50V"
			(at 0 0 0)
			(unlocked yes)
			(layer "F.Fab")
			(hide yes)
			(effects
				(font
					(size 1 1)
					(thickness 0.15)
				)
			)
		)
		(property "Dielectric" "X5R"
			(at 0 0 0)
			(unlocked yes)
			(layer "F.Fab")
			(hide yes)
			(effects
				(font
					(size 1 1)
					(thickness 0.15)
				)
			)
		)
		(sheetname "/DCDC/")
		(sheetfile "dcdc.kicad_sch")
		(attr smd)
		(fp_rect
			(start -0.925 -0.47)
			(end 0.925 0.47)
			(stroke
				(width 0.05)
				(type default)
			)
			(fill no)
			(layer "F.CrtYd")
		)
		(fp_line
			(start -0.494 -0.25)
			(end 0.504 -0.25)
			(stroke
				(width 0.15)
				(type solid)
			)
			(layer "F.Fab")
		)
		(fp_line
			(start -0.494 0.248)
			(end -0.494 -0.25)
			(stroke
				(width 0.15)
				(type solid)
			)
			(layer "F.Fab")
		)
		(fp_line
			(start 0.504 -0.25)
			(end 0.504 0.248)
			(stroke
				(width 0.15)
				(type solid)
			)
			(layer "F.Fab")
		)
		(fp_line
			(start 0.504 0.248)
			(end -0.494 0.248)
			(stroke
				(width 0.15)
				(type solid)
			)
			(layer "F.Fab")
		)
		(fp_text user "License: Apache-2.0"
			(at -0.939 5.799 0)
			(layer "F.Fab")
			(effects
				(font
					(size 0.7 0.7)
					(thickness 0.15)
				)
				(justify left bottom)
			)
		)
		(fp_text user "${REFERENCE}"
			(at -0.939 4.599 0)
			(layer "F.Fab")
			(effects
				(font
					(size 0.7 0.7)
					(thickness 0.15)
				)
				(justify left bottom)
			)
		)
		(fp_text user "Author: Antmicro"
			(at -0.939 3.399 0)
			(layer "F.Fab")
			(effects
				(font
					(size 0.7 0.7)
					(thickness 0.15)
				)
				(justify left bottom)
			)
		)
		(pad "1" smd roundrect
			(at -0.48 0)
			(size 0.59 0.64)
			(layers "F.Cu" "F.Mask" "F.Paste")
			(roundrect_rratio 0.25)
			(net 879 "/DCDC/12V_PHASE")
			(pintype "passive")
		)
		(pad "2" smd roundrect
			(at 0.48 0)
			(size 0.59 0.64)
			(layers "F.Cu" "F.Mask" "F.Paste")
			(roundrect_rratio 0.25)
			(net 585 "/DCDC/12V_BOOT")
			(pintype "passive")
		)
	)
)
